(kicad_pcb
	(version 20260206)
	(generator "pcbnew")
	(generator_version "10.0")
	(general
		(thickness 1.6)
		(legacy_teardrops no)
	)
	(paper "A4")
	(title_block
		(title "timecard-production-celestica-r4006 — R4006-B0001-02_R01.brd")
		(comment 1 "Time Appliance Project (Time Card) / footprint 197 of 1113 (U24), pads 225-337 of 484")
	)
	(layers
		(0 "F.Cu" signal "TOP")
		(4 "In1.Cu" signal "L02_GND1")
		(6 "In2.Cu" signal "L03_SIG1")
		(8 "In3.Cu" signal "L04_GND2")
		(10 "In4.Cu" signal "L05_VCC1")
		(12 "In5.Cu" signal "L06_VCC2")
		(14 "In6.Cu" signal "L07_GND3")
		(16 "In7.Cu" signal "L08_SIG2")
		(18 "In8.Cu" signal "L09_GND4")
		(2 "B.Cu" signal "BOTTOM")
		(9 "F.Adhes" user "F.Adhesive")
		(11 "B.Adhes" user "B.Adhesive")
		(13 "F.Paste" user "Package Geometry/Pastemask Top")
		(15 "B.Paste" user "Package Geometry/Pastemask Bottom")
		(5 "F.SilkS" user "Ref Des/Silkscreen Top")
		(7 "B.SilkS" user "Ref Des/Silkscreen Bottom")
		(1 "F.Mask" user "Board Geometry/Soldermask Top")
		(3 "B.Mask" user "Board Geometry/Soldermask Bottom")
		(17 "Dwgs.User" user "User.Drawings")
		(19 "Cmts.User" user "User.Comments")
		(21 "Eco1.User" user "User.Eco1")
		(23 "Eco2.User" user "User.Eco2")
		(25 "Edge.Cuts" user "Board Geometry/Outline")
		(27 "Margin" user)
		(31 "F.CrtYd" user "Package Geometry/Place Bound Top")
		(29 "B.CrtYd" user "Package Geometry/Place Bound Bottom")
		(35 "F.Fab" user "Ref Des/Assembly Top")
		(33 "B.Fab" user "Ref Des/Assembly Bottom")
	)
	(footprint ""
		(layer "F.Cu")
		(at 109.347 -44.323 90)
		(property "Reference" "U24"
			(at 12.27963 3.683 0)
			(unlocked yes)
			(layer "F.SilkS")
			(effects
				(font
					(size 0.7874 0.5842)
					(thickness 0.1524)
				)
			)
		)
		(property "Value" ""
			(at 0 0 90)
			(layer "F.Fab")
			(effects
				(font
					(size 1.27 1.27)
				)
			)
		)
		(property "User Part Number" "PARTNUM*"
			(at 0 14.056868 90)
			(unlocked yes)
			(layer "Cmts.User")
			(hide yes)
			(effects
				(font
					(size 0.7874 0.5842)
					(thickness 0.1524)
				)
			)
		)
		(property "Device Type" "XC7A200T_2FBG484C_FBG484-G240-A"
			(at 0 12.863068 90)
			(unlocked yes)
			(layer "F.Fab")
			(hide yes)
			(effects
				(font
					(size 0.7874 0.5842)
					(thickness 0.1524)
				)
			)
		)
		(duplicate_pad_numbers_are_jumpers no)
		(pad "J5" smd circle
			(at -6.49986 -2.499868 90)
			(size 0.50038 0.50038)
			(layers "F.Cu" "F.Mask" "F.Paste")
			(net "Net_92")
		)
		(pad "J6" smd circle
			(at -5.499862 -2.499868 90)
			(size 0.50038 0.50038)
			(layers "F.Cu" "F.Mask" "F.Paste")
			(net "Net_116")
		)
		(pad "J7" smd circle
			(at -4.499864 -2.499868 90)
			(size 0.50038 0.50038)
			(layers "F.Cu" "F.Mask" "F.Paste")
			(net "XP1R0V_FPGA_VCCINT")
		)
		(pad "J8" smd circle
			(at -3.499866 -2.499868 90)
			(size 0.50038 0.50038)
			(layers "F.Cu" "F.Mask" "F.Paste")
			(net "SG")
		)
		(pad "J9" smd circle
			(at -2.499868 -2.499868 90)
			(size 0.50038 0.50038)
			(layers "F.Cu" "F.Mask" "F.Paste")
			(net "XP1R0V_FPGA_VCCINT")
		)
		(pad "J10" smd circle
			(at -1.49987 -2.499868 90)
			(size 0.50038 0.50038)
			(layers "F.Cu" "F.Mask" "F.Paste")
			(net "SG")
		)
		(pad "J11" smd circle
			(at -0.499872 -2.499868 90)
			(size 0.50038 0.50038)
			(layers "F.Cu" "F.Mask" "F.Paste")
			(net "XP1R0V_FPGA_VCCINT")
		)
		(pad "J12" smd circle
			(at 0.500126 -2.499868 90)
			(size 0.50038 0.50038)
			(layers "F.Cu" "F.Mask" "F.Paste")
			(net "SG")
		)
		(pad "J13" smd circle
			(at 1.500124 -2.499868 90)
			(size 0.50038 0.50038)
			(layers "F.Cu" "F.Mask" "F.Paste")
			(net "XP3R3V_FPGA")
		)
		(pad "J14" smd circle
			(at 2.500122 -2.499868 90)
			(size 0.50038 0.50038)
			(layers "F.Cu" "F.Mask" "F.Paste")
			(net "SMA4_SIG_IN_BF_EN_N")
		)
		(pad "J15" smd circle
			(at 3.50012 -2.499868 90)
			(size 0.50038 0.50038)
			(layers "F.Cu" "F.Mask" "F.Paste")
			(net "SMA3_SIG_OUT_BF_EN_N")
		)
		(pad "J16" smd circle
			(at 4.500118 -2.499868 90)
			(size 0.50038 0.50038)
			(layers "F.Cu" "F.Mask" "F.Paste")
			(net "Net_90")
		)
		(pad "J17" smd circle
			(at 5.500116 -2.499868 90)
			(size 0.50038 0.50038)
			(layers "F.Cu" "F.Mask" "F.Paste")
			(net "FPGA_OUT_BNO080_RST_N")
		)
		(pad "J18" smd circle
			(at 6.500114 -2.499868 90)
			(size 0.50038 0.50038)
			(layers "F.Cu" "F.Mask" "F.Paste")
			(net "SG")
		)
		(pad "J19" smd circle
			(at 7.500112 -2.499868 90)
			(size 0.50038 0.50038)
			(layers "F.Cu" "F.Mask" "F.Paste")
			(net "FPGA_IN_SHT3X_ALERT_N")
		)
		(pad "J20" smd circle
			(at 8.50011 -2.499868 90)
			(size 0.50038 0.50038)
			(layers "F.Cu" "F.Mask" "F.Paste")
			(net "FPGA_IN_RST_DLY_N")
		)
		(pad "J21" smd circle
			(at 9.500108 -2.499868 90)
			(size 0.50038 0.50038)
			(layers "F.Cu" "F.Mask" "F.Paste")
			(net "Net_93")
		)
		(pad "J22" smd circle
			(at 10.500106 -2.499868 90)
			(size 0.50038 0.50038)
			(layers "F.Cu" "F.Mask" "F.Paste")
			(net "FPGA_IO_0")
		)
		(pad "K1" smd circle
			(at -10.500106 -1.49987 90)
			(size 0.50038 0.50038)
			(layers "F.Cu" "F.Mask" "F.Paste")
			(net "Net_155")
		)
		(pad "K2" smd circle
			(at -9.500108 -1.49987 90)
			(size 0.50038 0.50038)
			(layers "F.Cu" "F.Mask" "F.Paste")
			(net "Net_161")
		)
		(pad "K3" smd circle
			(at -8.50011 -1.49987 90)
			(size 0.50038 0.50038)
			(layers "F.Cu" "F.Mask" "F.Paste")
			(net "Net_105")
		)
		(pad "K4" smd circle
			(at -7.499858 -1.49987 90)
			(size 0.50038 0.50038)
			(layers "F.Cu" "F.Mask" "F.Paste")
			(net "Net_103")
		)
		(pad "K5" smd circle
			(at -6.49986 -1.49987 90)
			(size 0.50038 0.50038)
			(layers "F.Cu" "F.Mask" "F.Paste")
			(net "SG")
		)
		(pad "K6" smd circle
			(at -5.499862 -1.49987 90)
			(size 0.50038 0.50038)
			(layers "F.Cu" "F.Mask" "F.Paste")
			(net "Net_118")
		)
		(pad "K7" smd circle
			(at -4.499864 -1.49987 90)
			(size 0.50038 0.50038)
			(layers "F.Cu" "F.Mask" "F.Paste")
			(net "SG")
		)
		(pad "K8" smd circle
			(at -3.499866 -1.49987 90)
			(size 0.50038 0.50038)
			(layers "F.Cu" "F.Mask" "F.Paste")
			(net "XP1R0V_FPGA_VCCINT")
		)
		(pad "K9" smd circle
			(at -2.499868 -1.49987 90)
			(size 0.50038 0.50038)
			(layers "F.Cu" "F.Mask" "F.Paste")
			(net "SG")
		)
		(pad "K10" smd circle
			(at -1.49987 -1.49987 90)
			(size 0.50038 0.50038)
			(layers "F.Cu" "F.Mask" "F.Paste")
			(net "XP1R8V_FPGA_VCCAUX")
		)
		(pad "K11" smd circle
			(at -0.499872 -1.49987 90)
			(size 0.50038 0.50038)
			(layers "F.Cu" "F.Mask" "F.Paste")
			(net "SG")
		)
		(pad "K12" smd circle
			(at 0.500126 -1.49987 90)
			(size 0.50038 0.50038)
			(layers "F.Cu" "F.Mask" "F.Paste")
			(net "XP1R8V_FPGA_VCCAUX")
		)
		(pad "K13" smd circle
			(at 1.500124 -1.49987 90)
			(size 0.50038 0.50038)
			(layers "F.Cu" "F.Mask" "F.Paste")
			(net "SMA1_SIG_OUT_BF_EN_N")
		)
		(pad "K14" smd circle
			(at 2.500122 -1.49987 90)
			(size 0.50038 0.50038)
			(layers "F.Cu" "F.Mask" "F.Paste")
			(net "SMA1_SIG_IN_BF_EN_N")
		)
		(pad "K15" smd circle
			(at 3.50012 -1.49987 90)
			(size 0.50038 0.50038)
			(layers "F.Cu" "F.Mask" "F.Paste")
			(net "SG")
		)
		(pad "K16" smd circle
			(at 4.500118 -1.49987 90)
			(size 0.50038 0.50038)
			(layers "F.Cu" "F.Mask" "F.Paste")
			(net "FPGA_OUT_I2C_BUFFER_EN")
		)
		(pad "K17" smd circle
			(at 5.500116 -1.49987 90)
			(size 0.50038 0.50038)
			(layers "F.Cu" "F.Mask" "F.Paste")
			(net "Net_171")
		)
		(pad "K18" smd circle
			(at 6.500114 -1.49987 90)
			(size 0.50038 0.50038)
			(layers "F.Cu" "F.Mask" "F.Paste")
			(net "Net_35")
		)
		(pad "K19" smd circle
			(at 7.500112 -1.49987 90)
			(size 0.50038 0.50038)
			(layers "F.Cu" "F.Mask" "F.Paste")
			(net "Net_33")
		)
		(pad "K20" smd circle
			(at 8.50011 -1.49987 90)
			(size 0.50038 0.50038)
			(layers "F.Cu" "F.Mask" "F.Paste")
			(net "XP3R3V_FPGA")
		)
		(pad "K21" smd circle
			(at 9.500108 -1.49987 90)
			(size 0.50038 0.50038)
			(layers "F.Cu" "F.Mask" "F.Paste")
			(net "FPGA_IO_4")
		)
		(pad "K22" smd circle
			(at 10.500106 -1.49987 90)
			(size 0.50038 0.50038)
			(layers "F.Cu" "F.Mask" "F.Paste")
			(net "FPGA_IO_5")
		)
		(pad "L1" smd circle
			(at -10.500106 -0.499872 90)
			(size 0.50038 0.50038)
			(layers "F.Cu" "F.Mask" "F.Paste")
			(net "Net_109")
		)
		(pad "L2" smd circle
			(at -9.500108 -0.499872 90)
			(size 0.50038 0.50038)
			(layers "F.Cu" "F.Mask" "F.Paste")
			(net "SG")
		)
		(pad "L3" smd circle
			(at -8.50011 -0.499872 90)
			(size 0.50038 0.50038)
			(layers "F.Cu" "F.Mask" "F.Paste")
			(net "Net_107")
		)
		(pad "L4" smd circle
			(at -7.499858 -0.499872 90)
			(size 0.50038 0.50038)
			(layers "F.Cu" "F.Mask" "F.Paste")
			(net "Net_119")
		)
		(pad "L5" smd circle
			(at -6.49986 -0.499872 90)
			(size 0.50038 0.50038)
			(layers "F.Cu" "F.Mask" "F.Paste")
			(net "Net_120")
		)
		(pad "L6" smd circle
			(at -5.499862 -0.499872 90)
			(size 0.50038 0.50038)
			(layers "F.Cu" "F.Mask" "F.Paste")
			(net "Net_89")
		)
		(pad "L7" smd circle
			(at -4.499864 -0.499872 90)
			(size 0.50038 0.50038)
			(layers "F.Cu" "F.Mask" "F.Paste")
			(net "XP1R0V_FPGA_VCCINT")
		)
		(pad "L8" smd circle
			(at -3.499866 -0.499872 90)
			(size 0.50038 0.50038)
			(layers "F.Cu" "F.Mask" "F.Paste")
			(net "SG")
		)
		(pad "L9" smd circle
			(at -2.499868 -0.499872 90)
			(size 0.50038 0.50038)
			(layers "F.Cu" "F.Mask" "F.Paste")
			(net "SG")
		)
		(pad "L10" smd circle
			(at -1.49987 -0.499872 90)
			(size 0.50038 0.50038)
			(layers "F.Cu" "F.Mask" "F.Paste")
			(net "SG")
		)
		(pad "L11" smd circle
			(at -0.499872 -0.499872 90)
			(size 0.50038 0.50038)
			(layers "F.Cu" "F.Mask" "F.Paste")
			(net "XP1R0V_FPGA_VCCINT")
		)
		(pad "L12" smd circle
			(at 0.500126 -0.499872 90)
			(size 0.50038 0.50038)
			(layers "F.Cu" "F.Mask" "F.Paste")
			(net "CCLK_0")
		)
		(pad "L13" smd circle
			(at 1.500124 -0.499872 90)
			(size 0.50038 0.50038)
			(layers "F.Cu" "F.Mask" "F.Paste")
			(net "SMA2_SIG_IN_BF_EN_N")
		)
		(pad "L14" smd circle
			(at 2.500122 -0.499872 90)
			(size 0.50038 0.50038)
			(layers "F.Cu" "F.Mask" "F.Paste")
			(net "FPGA_IN_BNO080_INT_N")
		)
		(pad "L15" smd circle
			(at 3.50012 -0.499872 90)
			(size 0.50038 0.50038)
			(layers "F.Cu" "F.Mask" "F.Paste")
			(net "FPGA_OUT_BNO080_BOOT_N")
		)
		(pad "L16" smd circle
			(at 4.500118 -0.499872 90)
			(size 0.50038 0.50038)
			(layers "F.Cu" "F.Mask" "F.Paste")
			(net "Net_172")
		)
		(pad "L17" smd circle
			(at 5.500116 -0.499872 90)
			(size 0.50038 0.50038)
			(layers "F.Cu" "F.Mask" "F.Paste")
			(net "XP3R3V_FPGA")
		)
		(pad "L18" smd circle
			(at 6.500114 -0.499872 90)
			(size 0.50038 0.50038)
			(layers "F.Cu" "F.Mask" "F.Paste")
			(net "Net_45")
		)
		(pad "L19" smd circle
			(at 7.500112 -0.499872 90)
			(size 0.50038 0.50038)
			(layers "F.Cu" "F.Mask" "F.Paste")
			(net "Net_37")
		)
		(pad "L20" smd circle
			(at 8.50011 -0.499872 90)
			(size 0.50038 0.50038)
			(layers "F.Cu" "F.Mask" "F.Paste")
			(net "Net_36")
		)
		(pad "L21" smd circle
			(at 9.500108 -0.499872 90)
			(size 0.50038 0.50038)
			(layers "F.Cu" "F.Mask" "F.Paste")
			(net "FPGA_IO_7")
		)
		(pad "L22" smd circle
			(at 10.500106 -0.499872 90)
			(size 0.50038 0.50038)
			(layers "F.Cu" "F.Mask" "F.Paste")
			(net "SG")
		)
		(pad "M1" smd circle
			(at -10.500106 0.500126 90)
			(size 0.50038 0.50038)
			(layers "F.Cu" "F.Mask" "F.Paste")
			(net "Net_111")
		)
		(pad "M2" smd circle
			(at -9.500108 0.500126 90)
			(size 0.50038 0.50038)
			(layers "F.Cu" "F.Mask" "F.Paste")
			(net "Net_113")
		)
		(pad "M3" smd circle
			(at -8.50011 0.500126 90)
			(size 0.50038 0.50038)
			(layers "F.Cu" "F.Mask" "F.Paste")
			(net "Net_115")
		)
		(pad "M4" smd circle
			(at -7.499858 0.500126 90)
			(size 0.50038 0.50038)
			(layers "F.Cu" "F.Mask" "F.Paste")
			(net "XP2R5V_FPGA")
		)
		(pad "M5" smd circle
			(at -6.49986 0.500126 90)
			(size 0.50038 0.50038)
			(layers "F.Cu" "F.Mask" "F.Paste")
			(net "IO_L23N_35")
		)
		(pad "M6" smd circle
			(at -5.499862 0.500126 90)
			(size 0.50038 0.50038)
			(layers "F.Cu" "F.Mask" "F.Paste")
			(net "IO_L23P_35")
		)
		(pad "M7" smd circle
			(at -4.499864 0.500126 90)
			(size 0.50038 0.50038)
			(layers "F.Cu" "F.Mask" "F.Paste")
			(net "SG")
		)
		(pad "M8" smd circle
			(at -3.499866 0.500126 90)
			(size 0.50038 0.50038)
			(layers "F.Cu" "F.Mask" "F.Paste")
			(net "XP1R0V_FPGA_VCCINT")
		)
		(pad "M9" smd circle
			(at -2.499868 0.500126 90)
			(size 0.50038 0.50038)
			(layers "F.Cu" "F.Mask" "F.Paste")
			(net "SG")
		)
		(pad "M10" smd circle
			(at -1.49987 0.500126 90)
			(size 0.50038 0.50038)
			(layers "F.Cu" "F.Mask" "F.Paste")
			(net "SG")
		)
		(pad "M11" smd circle
			(at -0.499872 0.500126 90)
			(size 0.50038 0.50038)
			(layers "F.Cu" "F.Mask" "F.Paste")
			(net "SG")
		)
		(pad "M12" smd circle
			(at 0.500126 0.500126 90)
			(size 0.50038 0.50038)
			(layers "F.Cu" "F.Mask" "F.Paste")
			(net "XP1R8V_FPGA_VCCAUX")
		)
		(pad "M13" smd circle
			(at 1.500124 0.500126 90)
			(size 0.50038 0.50038)
			(layers "F.Cu" "F.Mask" "F.Paste")
			(net "SMA2_SIG_OUT_BF_EN_N")
		)
		(pad "M14" smd circle
			(at 2.500122 0.500126 90)
			(size 0.50038 0.50038)
			(layers "F.Cu" "F.Mask" "F.Paste")
			(net "XP3R3V_FPGA")
		)
		(pad "M15" smd circle
			(at 3.50012 0.500126 90)
			(size 0.50038 0.50038)
			(layers "F.Cu" "F.Mask" "F.Paste")
			(net "FPGA_IN_MAC_USB_OC_N")
		)
		(pad "M16" smd circle
			(at 4.500118 0.500126 90)
			(size 0.50038 0.50038)
			(layers "F.Cu" "F.Mask" "F.Paste")
			(net "RSVD_DBG_USB_MUX_SEL")
		)
		(pad "M17" smd circle
			(at 5.500116 0.500126 90)
			(size 0.50038 0.50038)
			(layers "F.Cu" "F.Mask" "F.Paste")
			(net "Net_127")
		)
		(pad "M18" smd circle
			(at 6.500114 0.500126 90)
			(size 0.50038 0.50038)
			(layers "F.Cu" "F.Mask" "F.Paste")
			(net "FPGA_IN_LM75B_INT3_N")
		)
		(pad "M19" smd circle
			(at 7.500112 0.500126 90)
			(size 0.50038 0.50038)
			(layers "F.Cu" "F.Mask" "F.Paste")
			(net "SG")
		)
		(pad "M20" smd circle
			(at 8.50011 0.500126 90)
			(size 0.50038 0.50038)
			(layers "F.Cu" "F.Mask" "F.Paste")
			(net "Net_50")
		)
		(pad "M21" smd circle
			(at 9.500108 0.500126 90)
			(size 0.50038 0.50038)
			(layers "F.Cu" "F.Mask" "F.Paste")
			(net "FPGA_IO_6")
		)
		(pad "M22" smd circle
			(at 10.500106 0.500126 90)
			(size 0.50038 0.50038)
			(layers "F.Cu" "F.Mask" "F.Paste")
			(net "FPGA_IN_LM75B_INT2_N")
		)
		(pad "N1" smd circle
			(at -10.500106 1.500124 90)
			(size 0.50038 0.50038)
			(layers "F.Cu" "F.Mask" "F.Paste")
			(net "XP2R5V_FPGA")
		)
		(pad "N2" smd circle
			(at -9.500108 1.500124 90)
			(size 0.50038 0.50038)
			(layers "F.Cu" "F.Mask" "F.Paste")
			(net "IO_L22N_35")
		)
		(pad "N3" smd circle
			(at -8.50011 1.500124 90)
			(size 0.50038 0.50038)
			(layers "F.Cu" "F.Mask" "F.Paste")
			(net "Net_121")
		)
		(pad "N4" smd circle
			(at -7.499858 1.500124 90)
			(size 0.50038 0.50038)
			(layers "F.Cu" "F.Mask" "F.Paste")
			(net "Net_122")
		)
		(pad "N5" smd circle
			(at -6.49986 1.500124 90)
			(size 0.50038 0.50038)
			(layers "F.Cu" "F.Mask" "F.Paste")
			(net "IO_L24N_35")
		)
		(pad "N6" smd circle
			(at -5.499862 1.500124 90)
			(size 0.50038 0.50038)
			(layers "F.Cu" "F.Mask" "F.Paste")
			(net "SG")
		)
		(pad "N7" smd circle
			(at -4.499864 1.500124 90)
			(size 0.50038 0.50038)
			(layers "F.Cu" "F.Mask" "F.Paste")
			(net "XP1R0V_FPGA_VCCINT")
		)
		(pad "N8" smd circle
			(at -3.499866 1.500124 90)
			(size 0.50038 0.50038)
			(layers "F.Cu" "F.Mask" "F.Paste")
			(net "SG")
		)
		(pad "N9" smd circle
			(at -2.499868 1.500124 90)
			(size 0.50038 0.50038)
			(layers "F.Cu" "F.Mask" "F.Paste")
			(net "SG")
		)
		(pad "N10" smd circle
			(at -1.49987 1.500124 90)
			(size 0.50038 0.50038)
			(layers "F.Cu" "F.Mask" "F.Paste")
			(net "SG")
		)
		(pad "N11" smd circle
			(at -0.499872 1.500124 90)
			(size 0.50038 0.50038)
			(layers "F.Cu" "F.Mask" "F.Paste")
			(net "XP1R0V_FPGA_VCCINT")
		)
		(pad "N12" smd circle
			(at 0.500126 1.500124 90)
			(size 0.50038 0.50038)
			(layers "F.Cu" "F.Mask" "F.Paste")
			(net "FPGA_PROGRAM_N")
		)
		(pad "N13" smd circle
			(at 1.500124 1.500124 90)
			(size 0.50038 0.50038)
			(layers "F.Cu" "F.Mask" "F.Paste")
			(net "Net_66")
		)
		(pad "N14" smd circle
			(at 2.500122 1.500124 90)
			(size 0.50038 0.50038)
			(layers "F.Cu" "F.Mask" "F.Paste")
			(net "Net_65")
		)
		(pad "N15" smd circle
			(at 3.50012 1.500124 90)
			(size 0.50038 0.50038)
			(layers "F.Cu" "F.Mask" "F.Paste")
			(net "UART_GPS_TX_FPGA_RX")
		)
		(pad "N16" smd circle
			(at 4.500118 1.500124 90)
			(size 0.50038 0.50038)
			(layers "F.Cu" "F.Mask" "F.Paste")
			(net "SG")
		)
		(pad "N17" smd circle
			(at 5.500116 1.500124 90)
			(size 0.50038 0.50038)
			(layers "F.Cu" "F.Mask" "F.Paste")
			(net "FPGA_PCA9546_I2C_SCL")
		)
		(pad "N18" smd circle
			(at 6.500114 1.500124 90)
			(size 0.50038 0.50038)
			(layers "F.Cu" "F.Mask" "F.Paste")
			(net "FPGA_BRD_REV2")
		)
		(pad "N19" smd circle
			(at 7.500112 1.500124 90)
			(size 0.50038 0.50038)
			(layers "F.Cu" "F.Mask" "F.Paste")
			(net "FPGA_BRD_REV1")
		)
		(pad "N20" smd circle
			(at 8.50011 1.500124 90)
			(size 0.50038 0.50038)
			(layers "F.Cu" "F.Mask" "F.Paste")
			(net "FPGA_BRD_REV0")
		)
		(pad "N21" smd circle
			(at 9.500108 1.500124 90)
			(size 0.50038 0.50038)
			(layers "F.Cu" "F.Mask" "F.Paste")
			(net "XP3R3V_FPGA")
		)
		(pad "N22" smd circle
			(at 10.500106 1.500124 90)
			(size 0.50038 0.50038)
			(layers "F.Cu" "F.Mask" "F.Paste")
			(net "FPGA_IN_LM75B_INT1_N")
		)
		(pad "P1" smd circle
			(at -10.500106 2.500122 90)
			(size 0.50038 0.50038)
			(layers "F.Cu" "F.Mask" "F.Paste")
			(net "IO_L20N_35")
		)
		(pad "P2" smd circle
			(at -9.500108 2.500122 90)
			(size 0.50038 0.50038)
			(layers "F.Cu" "F.Mask" "F.Paste")
			(net "IO_L22P_35")
		)
		(pad "P3" smd circle
			(at -8.50011 2.500122 90)
			(size 0.50038 0.50038)
			(layers "F.Cu" "F.Mask" "F.Paste")
			(net "SG")
		)
		(pad "P4" smd circle
			(at -7.499858 2.500122 90)
			(size 0.50038 0.50038)
			(layers "F.Cu" "F.Mask" "F.Paste")
			(net "IO_L21N_35")
		)
		(pad "P5" smd circle
			(at -6.49986 2.500122 90)
			(size 0.50038 0.50038)
			(layers "F.Cu" "F.Mask" "F.Paste")
			(net "IO_L21P_35")
		)
		(pad "P6" smd circle
			(at -5.499862 2.500122 90)
			(size 0.50038 0.50038)
			(layers "F.Cu" "F.Mask" "F.Paste")
			(net "IO_L24P_35")
		)
		(pad "P7" smd circle
			(at -4.499864 2.500122 90)
			(size 0.50038 0.50038)
			(layers "F.Cu" "F.Mask" "F.Paste")
			(net "SG")
		)
	)
)
